(kicad_pcb
	(version 20260206)
	(generator "pcbnew")
	(generator_version "10.0")
	(general
		(thickness 1.6)
		(legacy_teardrops no)
	)
	(paper "A4")
	(title_block
		(title "01162023_DA0F0TEBIF0_F0T_Expander_BD_F_brd_V02_OCP.brd")
		(comment 1 "Grand Teton / footprints 5376-5382 of 9728")
	)
	(layers
		(0 "F.Cu" signal "TOP")
		(4 "In1.Cu" signal "GND")
		(6 "In2.Cu" signal "VCC")
		(8 "In3.Cu" signal "VCC1")
		(10 "In4.Cu" signal "GND1")
		(12 "In5.Cu" signal "IN1")
		(14 "In6.Cu" signal "GND2")
		(16 "In7.Cu" signal "IN2")
		(18 "In8.Cu" signal "GND3")
		(20 "In9.Cu" signal "IN3")
		(22 "In10.Cu" signal "GND4")
		(24 "In11.Cu" signal "IN4")
		(26 "In12.Cu" signal "GND5")
		(28 "In13.Cu" signal "IN5")
		(30 "In14.Cu" signal "GND6")
		(32 "In15.Cu" signal "IN6")
		(34 "In16.Cu" signal "GND7")
		(2 "B.Cu" signal "BOTTOM")
		(9 "F.Adhes" user "F.Adhesive")
		(11 "B.Adhes" user "B.Adhesive")
		(13 "F.Paste" user "Package Geometry/Pastemask Top")
		(15 "B.Paste" user "Package Geometry/Pastemask Bottom")
		(5 "F.SilkS" user "Ref Des/Silkscreen Top")
		(7 "B.SilkS" user "Ref Des/Silkscreen Bottom")
		(1 "F.Mask" user "Board Geometry/Soldermask Top")
		(3 "B.Mask" user "Board Geometry/Soldermask Bottom")
		(17 "Dwgs.User" user "User.Drawings")
		(19 "Cmts.User" user "User.Comments")
		(21 "Eco1.User" user "User.Eco1")
		(23 "Eco2.User" user "User.Eco2")
		(25 "Edge.Cuts" user "Board Geometry/Outline")
		(27 "Margin" user)
		(31 "F.CrtYd" user "Package Geometry/Place Bound Top")
		(29 "B.CrtYd" user "Package Geometry/Place Bound Bottom")
		(35 "F.Fab" user "Ref Des/Assembly Top")
		(33 "B.Fab" user "Ref Des/Assembly Bottom")
	)
	(footprint ""
		(layer "F.Cu")
		(at 224.514664 -204.44206 90)
		(property "Reference" "R5289"
			(at 0 0 90)
			(layer "F.SilkS")
			(hide yes)
			(effects
				(font
					(size 1.27 1.27)
				)
			)
		)
		(property "Value" ""
			(at 0 0 90)
			(layer "F.Fab")
			(effects
				(font
					(size 1.27 1.27)
				)
			)
		)
		(duplicate_pad_numbers_are_jumpers no)
		(fp_line
			(start 0.7874 -0.4064)
			(end 0.7874 0.4064)
			(stroke
				(width 0.1524)
				(type default)
			)
			(layer "F.SilkS")
		)
		(fp_line
			(start -0.7874 -0.4064)
			(end 0.7874 -0.4064)
			(stroke
				(width 0.1524)
				(type default)
			)
			(layer "F.SilkS")
		)
		(fp_line
			(start 0.7874 0.4064)
			(end -0.7874 0.4064)
			(stroke
				(width 0.1524)
				(type default)
			)
			(layer "F.SilkS")
		)
		(fp_line
			(start -0.7874 0.4064)
			(end -0.7874 -0.4064)
			(stroke
				(width 0.1524)
				(type default)
			)
			(layer "F.SilkS")
		)
		(fp_line
			(start -0.12065 -0.305054)
			(end -0.12065 -0.2794)
			(stroke
				(width 0.1)
				(type default)
			)
			(layer "F.Fab")
		)
		(fp_line
			(start -0.67945 -0.305054)
			(end -0.12065 -0.305054)
			(stroke
				(width 0.1)
				(type default)
			)
			(layer "F.Fab")
		)
		(fp_line
			(start 0.67945 -0.3048)
			(end 0.67945 0.3048)
			(stroke
				(width 0.1)
				(type default)
			)
			(layer "F.Fab")
		)
		(fp_line
			(start 0.12065 -0.3048)
			(end 0.67945 -0.3048)
			(stroke
				(width 0.1)
				(type default)
			)
			(layer "F.Fab")
		)
		(fp_line
			(start 0.12065 -0.2794)
			(end 0.12065 -0.3048)
			(stroke
				(width 0.1)
				(type default)
			)
			(layer "F.Fab")
		)
		(fp_line
			(start -0.12065 -0.2794)
			(end 0.12065 -0.2794)
			(stroke
				(width 0.1)
				(type default)
			)
			(layer "F.Fab")
		)
		(fp_line
			(start 0.120396 0.2794)
			(end -0.12065 0.2794)
			(stroke
				(width 0.1)
				(type default)
			)
			(layer "F.Fab")
		)
		(fp_line
			(start -0.12065 0.2794)
			(end -0.12065 0.3048)
			(stroke
				(width 0.1)
				(type default)
			)
			(layer "F.Fab")
		)
		(fp_line
			(start 0.67945 0.3048)
			(end 0.120396 0.3048)
			(stroke
				(width 0.1)
				(type default)
			)
			(layer "F.Fab")
		)
		(fp_line
			(start 0.120396 0.3048)
			(end 0.120396 0.2794)
			(stroke
				(width 0.1)
				(type default)
			)
			(layer "F.Fab")
		)
		(fp_line
			(start -0.12065 0.3048)
			(end -0.67945 0.3048)
			(stroke
				(width 0.1)
				(type default)
			)
			(layer "F.Fab")
		)
		(fp_line
			(start -0.67945 0.3048)
			(end -0.67945 -0.305054)
			(stroke
				(width 0.1)
				(type default)
			)
			(layer "F.Fab")
		)
		(pad "1" smd circle
			(at -0.40005 0 90)
			(size 0 0)
			(layers "F.Cu" "F.Mask" "F.Paste")
			(net "RST_SMB_NIC_MUX_R_N")
		)
		(pad "2" smd circle
			(at 0.40005 0 90)
			(size 0 0)
			(layers "F.Cu" "F.Mask" "F.Paste")
			(net "RST_SMB_NIC_MUX_N")
		)
	)
	(footprint ""
		(layer "F.Cu")
		(at 58.176922 -377.556268 180)
		(property "Reference" "R1824"
			(at 0 0 180)
			(layer "F.SilkS")
			(hide yes)
			(effects
				(font
					(size 1.27 1.27)
				)
			)
		)
		(property "Value" ""
			(at 0 0 180)
			(layer "F.Fab")
			(effects
				(font
					(size 1.27 1.27)
				)
			)
		)
		(duplicate_pad_numbers_are_jumpers no)
		(fp_line
			(start 0.7874 0.4064)
			(end -0.7874 0.4064)
			(stroke
				(width 0.1524)
				(type default)
			)
			(layer "F.SilkS")
		)
		(fp_line
			(start 0.7874 -0.4064)
			(end 0.7874 0.4064)
			(stroke
				(width 0.1524)
				(type default)
			)
			(layer "F.SilkS")
		)
		(fp_line
			(start -0.7874 0.4064)
			(end -0.7874 -0.4064)
			(stroke
				(width 0.1524)
				(type default)
			)
			(layer "F.SilkS")
		)
		(fp_line
			(start -0.7874 -0.4064)
			(end 0.7874 -0.4064)
			(stroke
				(width 0.1524)
				(type default)
			)
			(layer "F.SilkS")
		)
		(fp_line
			(start 0.67945 0.3048)
			(end 0.120396 0.3048)
			(stroke
				(width 0.1)
				(type default)
			)
			(layer "F.Fab")
		)
		(fp_line
			(start 0.67945 -0.3048)
			(end 0.67945 0.3048)
			(stroke
				(width 0.1)
				(type default)
			)
			(layer "F.Fab")
		)
		(fp_line
			(start 0.12065 -0.2794)
			(end 0.12065 -0.3048)
			(stroke
				(width 0.1)
				(type default)
			)
			(layer "F.Fab")
		)
		(fp_line
			(start 0.12065 -0.3048)
			(end 0.67945 -0.3048)
			(stroke
				(width 0.1)
				(type default)
			)
			(layer "F.Fab")
		)
		(fp_line
			(start 0.120396 0.3048)
			(end 0.120396 0.2794)
			(stroke
				(width 0.1)
				(type default)
			)
			(layer "F.Fab")
		)
		(fp_line
			(start 0.120396 0.2794)
			(end -0.12065 0.2794)
			(stroke
				(width 0.1)
				(type default)
			)
			(layer "F.Fab")
		)
		(fp_line
			(start -0.12065 0.3048)
			(end -0.67945 0.3048)
			(stroke
				(width 0.1)
				(type default)
			)
			(layer "F.Fab")
		)
		(fp_line
			(start -0.12065 0.2794)
			(end -0.12065 0.3048)
			(stroke
				(width 0.1)
				(type default)
			)
			(layer "F.Fab")
		)
		(fp_line
			(start -0.12065 -0.2794)
			(end 0.12065 -0.2794)
			(stroke
				(width 0.1)
				(type default)
			)
			(layer "F.Fab")
		)
		(fp_line
			(start -0.12065 -0.305054)
			(end -0.12065 -0.2794)
			(stroke
				(width 0.1)
				(type default)
			)
			(layer "F.Fab")
		)
		(fp_line
			(start -0.67945 0.3048)
			(end -0.67945 -0.305054)
			(stroke
				(width 0.1)
				(type default)
			)
			(layer "F.Fab")
		)
		(fp_line
			(start -0.67945 -0.305054)
			(end -0.12065 -0.305054)
			(stroke
				(width 0.1)
				(type default)
			)
			(layer "F.Fab")
		)
		(pad "1" smd circle
			(at -0.40005 0 180)
			(size 0 0)
			(layers "F.Cu" "F.Mask" "F.Paste")
			(net "GPU_BASE_PWR_GD_R")
		)
		(pad "2" smd circle
			(at 0.40005 0 180)
			(size 0 0)
			(layers "F.Cu" "F.Mask" "F.Paste")
			(net "GPU_BASE_PWR_GD")
		)
	)
	(footprint ""
		(layer "F.Cu")
		(at 117.175026 -307.130704 -90)
		(property "Reference" "C4207"
			(at 0 0 270)
			(layer "F.SilkS")
			(hide yes)
			(effects
				(font
					(size 1.27 1.27)
				)
			)
		)
		(property "Value" ""
			(at 0 0 270)
			(layer "F.Fab")
			(effects
				(font
					(size 1.27 1.27)
				)
			)
		)
		(duplicate_pad_numbers_are_jumpers no)
		(fp_line
			(start -1.2954 0.5842)
			(end -1.2954 -0.5842)
			(stroke
				(width 0.1524)
				(type default)
			)
			(layer "F.SilkS")
		)
		(fp_line
			(start 1.2954 0.5842)
			(end -1.2954 0.5842)
			(stroke
				(width 0.1524)
				(type default)
			)
			(layer "F.SilkS")
		)
		(fp_line
			(start -1.2954 -0.5842)
			(end 1.2954 -0.5842)
			(stroke
				(width 0.1524)
				(type default)
			)
			(layer "F.SilkS")
		)
		(fp_line
			(start 1.2954 -0.5842)
			(end 1.2954 0.5842)
			(stroke
				(width 0.1524)
				(type default)
			)
			(layer "F.SilkS")
		)
		(fp_line
			(start -0.8636 0.4572)
			(end -0.8636 0.4064)
			(stroke
				(width 0.1)
				(type default)
			)
			(layer "F.Fab")
		)
		(fp_line
			(start 0.8636 0.4572)
			(end -0.8636 0.4572)
			(stroke
				(width 0.1)
				(type default)
			)
			(layer "F.Fab")
		)
		(fp_line
			(start -1.1938 0.4064)
			(end -1.1938 -0.4064)
			(stroke
				(width 0.1)
				(type default)
			)
			(layer "F.Fab")
		)
		(fp_line
			(start -0.8636 0.4064)
			(end -1.1938 0.4064)
			(stroke
				(width 0.1)
				(type default)
			)
			(layer "F.Fab")
		)
		(fp_line
			(start 0.8636 0.4064)
			(end 0.8636 0.4572)
			(stroke
				(width 0.1)
				(type default)
			)
			(layer "F.Fab")
		)
		(fp_line
			(start 1.1938 0.4064)
			(end 0.8636 0.4064)
			(stroke
				(width 0.1)
				(type default)
			)
			(layer "F.Fab")
		)
		(fp_line
			(start -1.1938 -0.4064)
			(end -0.8636 -0.4064)
			(stroke
				(width 0.1)
				(type default)
			)
			(layer "F.Fab")
		)
		(fp_line
			(start -0.8636 -0.4064)
			(end -0.8636 -0.4572)
			(stroke
				(width 0.1)
				(type default)
			)
			(layer "F.Fab")
		)
		(fp_line
			(start 0.8636 -0.4064)
			(end 1.1938 -0.4064)
			(stroke
				(width 0.1)
				(type default)
			)
			(layer "F.Fab")
		)
		(fp_line
			(start 1.1938 -0.4064)
			(end 1.1938 0.4064)
			(stroke
				(width 0.1)
				(type default)
			)
			(layer "F.Fab")
		)
		(fp_line
			(start -0.8636 -0.4572)
			(end 0.8636 -0.4572)
			(stroke
				(width 0.1)
				(type default)
			)
			(layer "F.Fab")
		)
		(fp_line
			(start 0.8636 -0.4572)
			(end 0.8636 -0.4064)
			(stroke
				(width 0.1)
				(type default)
			)
			(layer "F.Fab")
		)
		(pad "1" smd rect
			(at -0.7366 0 180)
			(size 0.7112 0.8128)
			(layers "F.Cu" "F.Mask" "F.Paste")
			(net "P0V8_SERDES_VDDA_PEX0_C5")
		)
		(pad "2" smd rect
			(at 0.7366 0 180)
			(size 0.7112 0.8128)
			(layers "F.Cu" "F.Mask" "F.Paste")
			(net "GND")
		)
	)
	(footprint ""
		(layer "F.Cu")
		(at 51.311048 -356.244906 90)
		(property "Reference" "C2183"
			(at 0 0 90)
			(layer "F.SilkS")
			(hide yes)
			(effects
				(font
					(size 1.27 1.27)
				)
			)
		)
		(property "Value" ""
			(at 0 0 90)
			(layer "F.Fab")
			(effects
				(font
					(size 1.27 1.27)
				)
			)
		)
		(duplicate_pad_numbers_are_jumpers no)
		(fp_line
			(start 0.299974 -0.150114)
			(end 0.299974 0.150114)
			(stroke
				(width 0.1)
				(type default)
			)
			(layer "F.Fab")
		)
		(fp_line
			(start -0.299974 -0.150114)
			(end 0.299974 -0.150114)
			(stroke
				(width 0.1)
				(type default)
			)
			(layer "F.Fab")
		)
		(fp_line
			(start 0.299974 0.150114)
			(end -0.299974 0.150114)
			(stroke
				(width 0.1)
				(type default)
			)
			(layer "F.Fab")
		)
		(fp_line
			(start -0.299974 0.150114)
			(end -0.299974 -0.150114)
			(stroke
				(width 0.1)
				(type default)
			)
			(layer "F.Fab")
		)
		(pad "1" smd rect
			(at -0.2667 0 90)
			(size 0.3048 0.381)
			(layers "F.Cu" "F.Mask" "F.Paste")
			(net "P5E_PEX0_STN4_TX_DN<64>")
		)
		(pad "2" smd rect
			(at 0.2667 0 90)
			(size 0.3048 0.381)
			(layers "F.Cu" "F.Mask" "F.Paste")
			(net "P5E_PEX0_STN4_TX_C_DN<64>")
		)
	)
	(footprint ""
		(layer "F.Cu")
		(at 312.654696 -22.961346 90)
		(property "Reference" "R1701"
			(at 0 0 90)
			(layer "F.SilkS")
			(hide yes)
			(effects
				(font
					(size 1.27 1.27)
				)
			)
		)
		(property "Value" ""
			(at 0 0 90)
			(layer "F.Fab")
			(effects
				(font
					(size 1.27 1.27)
				)
			)
		)
		(duplicate_pad_numbers_are_jumpers no)
		(fp_line
			(start 0.7874 -0.4064)
			(end 0.7874 0.4064)
			(stroke
				(width 0.1524)
				(type default)
			)
			(layer "F.SilkS")
		)
		(fp_line
			(start -0.7874 -0.4064)
			(end 0.7874 -0.4064)
			(stroke
				(width 0.1524)
				(type default)
			)
			(layer "F.SilkS")
		)
		(fp_line
			(start 0.7874 0.4064)
			(end -0.7874 0.4064)
			(stroke
				(width 0.1524)
				(type default)
			)
			(layer "F.SilkS")
		)
		(fp_line
			(start -0.7874 0.4064)
			(end -0.7874 -0.4064)
			(stroke
				(width 0.1524)
				(type default)
			)
			(layer "F.SilkS")
		)
		(fp_line
			(start -0.12065 -0.305054)
			(end -0.12065 -0.2794)
			(stroke
				(width 0.1)
				(type default)
			)
			(layer "F.Fab")
		)
		(fp_line
			(start -0.67945 -0.305054)
			(end -0.12065 -0.305054)
			(stroke
				(width 0.1)
				(type default)
			)
			(layer "F.Fab")
		)
		(fp_line
			(start 0.67945 -0.3048)
			(end 0.67945 0.3048)
			(stroke
				(width 0.1)
				(type default)
			)
			(layer "F.Fab")
		)
		(fp_line
			(start 0.12065 -0.3048)
			(end 0.67945 -0.3048)
			(stroke
				(width 0.1)
				(type default)
			)
			(layer "F.Fab")
		)
		(fp_line
			(start 0.12065 -0.2794)
			(end 0.12065 -0.3048)
			(stroke
				(width 0.1)
				(type default)
			)
			(layer "F.Fab")
		)
		(fp_line
			(start -0.12065 -0.2794)
			(end 0.12065 -0.2794)
			(stroke
				(width 0.1)
				(type default)
			)
			(layer "F.Fab")
		)
		(fp_line
			(start 0.120396 0.2794)
			(end -0.12065 0.2794)
			(stroke
				(width 0.1)
				(type default)
			)
			(layer "F.Fab")
		)
		(fp_line
			(start -0.12065 0.2794)
			(end -0.12065 0.3048)
			(stroke
				(width 0.1)
				(type default)
			)
			(layer "F.Fab")
		)
		(fp_line
			(start 0.67945 0.3048)
			(end 0.120396 0.3048)
			(stroke
				(width 0.1)
				(type default)
			)
			(layer "F.Fab")
		)
		(fp_line
			(start 0.120396 0.3048)
			(end 0.120396 0.2794)
			(stroke
				(width 0.1)
				(type default)
			)
			(layer "F.Fab")
		)
		(fp_line
			(start -0.12065 0.3048)
			(end -0.67945 0.3048)
			(stroke
				(width 0.1)
				(type default)
			)
			(layer "F.Fab")
		)
		(fp_line
			(start -0.67945 0.3048)
			(end -0.67945 -0.305054)
			(stroke
				(width 0.1)
				(type default)
			)
			(layer "F.Fab")
		)
		(pad "1" smd circle
			(at -0.40005 0 90)
			(size 0 0)
			(layers "F.Cu" "F.Mask" "F.Paste")
			(net "SMB_SSD10_ISO_EN")
		)
		(pad "2" smd circle
			(at 0.40005 0 90)
			(size 0 0)
			(layers "F.Cu" "F.Mask" "F.Paste")
			(net "P3V3_AUX")
		)
	)
	(footprint ""
		(layer "F.Cu")
		(at 252.634496 -30.03169 180)
		(property "Reference" "C492"
			(at 0 0 180)
			(layer "F.SilkS")
			(hide yes)
			(effects
				(font
					(size 1.27 1.27)
				)
			)
		)
		(property "Value" ""
			(at 0 0 180)
			(layer "F.Fab")
			(effects
				(font
					(size 1.27 1.27)
				)
			)
		)
		(duplicate_pad_numbers_are_jumpers no)
		(fp_line
			(start 0.299974 0.150114)
			(end -0.299974 0.150114)
			(stroke
				(width 0.1)
				(type default)
			)
			(layer "F.Fab")
		)
		(fp_line
			(start 0.299974 -0.150114)
			(end 0.299974 0.150114)
			(stroke
				(width 0.1)
				(type default)
			)
			(layer "F.Fab")
		)
		(fp_line
			(start -0.299974 0.150114)
			(end -0.299974 -0.150114)
			(stroke
				(width 0.1)
				(type default)
			)
			(layer "F.Fab")
		)
		(fp_line
			(start -0.299974 -0.150114)
			(end 0.299974 -0.150114)
			(stroke
				(width 0.1)
				(type default)
			)
			(layer "F.Fab")
		)
		(pad "1" smd rect
			(at -0.2667 0 180)
			(size 0.3048 0.381)
			(layers "F.Cu" "F.Mask" "F.Paste")
			(net "P5E_PEX2_STN2_TX_DN<45>")
		)
		(pad "2" smd rect
			(at 0.2667 0 180)
			(size 0.3048 0.381)
			(layers "F.Cu" "F.Mask" "F.Paste")
			(net "P5E_PEX2_STN2_TX_C_DN<45>")
		)
	)
	(footprint ""
		(layer "F.Cu")
		(at 206.622396 -90.104214)
		(property "Reference" "R4359"
			(at 0 0 0)
			(layer "F.SilkS")
			(hide yes)
			(effects
				(font
					(size 1.27 1.27)
				)
			)
		)
		(property "Value" ""
			(at 0 0 0)
			(layer "F.Fab")
			(effects
				(font
					(size 1.27 1.27)
				)
			)
		)
		(duplicate_pad_numbers_are_jumpers no)
		(fp_line
			(start -0.7874 -0.4064)
			(end 0.7874 -0.4064)
			(stroke
				(width 0.1524)
				(type default)
			)
			(layer "F.SilkS")
		)
		(fp_line
			(start -0.7874 0.4064)
			(end -0.7874 -0.4064)
			(stroke
				(width 0.1524)
				(type default)
			)
			(layer "F.SilkS")
		)
		(fp_line
			(start 0.7874 -0.4064)
			(end 0.7874 0.4064)
			(stroke
				(width 0.1524)
				(type default)
			)
			(layer "F.SilkS")
		)
		(fp_line
			(start 0.7874 0.4064)
			(end -0.7874 0.4064)
			(stroke
				(width 0.1524)
				(type default)
			)
			(layer "F.SilkS")
		)
		(fp_line
			(start -0.67945 -0.305054)
			(end -0.12065 -0.305054)
			(stroke
				(width 0.1)
				(type default)
			)
			(layer "F.Fab")
		)
		(fp_line
			(start -0.67945 0.3048)
			(end -0.67945 -0.305054)
			(stroke
				(width 0.1)
				(type default)
			)
			(layer "F.Fab")
		)
		(fp_line
			(start -0.12065 -0.305054)
			(end -0.12065 -0.2794)
			(stroke
				(width 0.1)
				(type default)
			)
			(layer "F.Fab")
		)
		(fp_line
			(start -0.12065 -0.2794)
			(end 0.12065 -0.2794)
			(stroke
				(width 0.1)
				(type default)
			)
			(layer "F.Fab")
		)
		(fp_line
			(start -0.12065 0.2794)
			(end -0.12065 0.3048)
			(stroke
				(width 0.1)
				(type default)
			)
			(layer "F.Fab")
		)
		(fp_line
			(start -0.12065 0.3048)
			(end -0.67945 0.3048)
			(stroke
				(width 0.1)
				(type default)
			)
			(layer "F.Fab")
		)
		(fp_line
			(start 0.120396 0.2794)
			(end -0.12065 0.2794)
			(stroke
				(width 0.1)
				(type default)
			)
			(layer "F.Fab")
		)
		(fp_line
			(start 0.120396 0.3048)
			(end 0.120396 0.2794)
			(stroke
				(width 0.1)
				(type default)
			)
			(layer "F.Fab")
		)
		(fp_line
			(start 0.12065 -0.3048)
			(end 0.67945 -0.3048)
			(stroke
				(width 0.1)
				(type default)
			)
			(layer "F.Fab")
		)
		(fp_line
			(start 0.12065 -0.2794)
			(end 0.12065 -0.3048)
			(stroke
				(width 0.1)
				(type default)
			)
			(layer "F.Fab")
		)
		(fp_line
			(start 0.67945 -0.3048)
			(end 0.67945 0.3048)
			(stroke
				(width 0.1)
				(type default)
			)
			(layer "F.Fab")
		)
		(fp_line
			(start 0.67945 0.3048)
			(end 0.120396 0.3048)
			(stroke
				(width 0.1)
				(type default)
			)
			(layer "F.Fab")
		)
		(pad "1" smd circle
			(at -0.40005 0)
			(size 0 0)
			(layers "F.Cu" "F.Mask" "F.Paste")
			(net "P3V3_AUX")
		)
		(pad "2" smd circle
			(at 0.40005 0)
			(size 0 0)
			(layers "F.Cu" "F.Mask" "F.Paste")
			(net "IRQ_SSD_LED_IOEXP_N")
		)
	)
)
